(kicad_pcb
	(version 20260206)
	(generator "pcbnew")
	(generator_version "10.0")
	(general
		(thickness 1.6)
		(legacy_teardrops no)
	)
	(paper "A4")
	(title_block
		(title "04192023_DAF0TMB3IC0_F0TG_MB_C_brd_V02_OCP.brd")
		(comment 1 "Grand Teton / footprints 261-268 of 8354")
	)
	(layers
		(0 "F.Cu" signal "TOP")
		(4 "In1.Cu" signal "GND")
		(6 "In2.Cu" signal "IN1")
		(8 "In3.Cu" signal "GND1")
		(10 "In4.Cu" signal "IN2")
		(12 "In5.Cu" signal "GND2")
		(14 "In6.Cu" signal "IN3")
		(16 "In7.Cu" signal "GND3")
		(18 "In8.Cu" signal "VCC")
		(20 "In9.Cu" signal "VCC1")
		(22 "In10.Cu" signal "GND4")
		(24 "In11.Cu" signal "IN4")
		(26 "In12.Cu" signal "GND5")
		(28 "In13.Cu" signal "IN5")
		(30 "In14.Cu" signal "GND6")
		(32 "In15.Cu" signal "IN6")
		(34 "In16.Cu" signal "GND7")
		(2 "B.Cu" signal "BOTTOM")
		(9 "F.Adhes" user "F.Adhesive")
		(11 "B.Adhes" user "B.Adhesive")
		(13 "F.Paste" user "Package Geometry/Pastemask Top")
		(15 "B.Paste" user "Package Geometry/Pastemask Bottom")
		(5 "F.SilkS" user "Ref Des/Silkscreen Top")
		(7 "B.SilkS" user "Ref Des/Silkscreen Bottom")
		(1 "F.Mask" user "Board Geometry/Soldermask Top")
		(3 "B.Mask" user "Board Geometry/Soldermask Bottom")
		(17 "Dwgs.User" user "User.Drawings")
		(19 "Cmts.User" user "User.Comments")
		(21 "Eco1.User" user "User.Eco1")
		(23 "Eco2.User" user "User.Eco2")
		(25 "Edge.Cuts" user "Board Geometry/Outline")
		(27 "Margin" user)
		(31 "F.CrtYd" user "Package Geometry/Place Bound Top")
		(29 "B.CrtYd" user "Package Geometry/Place Bound Bottom")
		(35 "F.Fab" user "Ref Des/Assembly Top")
		(33 "B.Fab" user "Ref Des/Assembly Bottom")
	)
	(footprint ""
		(layer "F.Cu")
		(at 180.975 -129.377948 -90)
		(property "Reference" "R272"
			(at 0 0 270)
			(layer "F.SilkS")
			(hide yes)
			(effects
				(font
					(size 1.27 1.27)
				)
			)
		)
		(property "Value" ""
			(at 0 0 270)
			(layer "F.Fab")
			(effects
				(font
					(size 1.27 1.27)
				)
			)
		)
		(duplicate_pad_numbers_are_jumpers no)
		(fp_line
			(start -0.7874 0.4064)
			(end -0.7874 -0.4064)
			(stroke
				(width 0.1524)
				(type default)
			)
			(layer "F.SilkS")
		)
		(fp_line
			(start 0.7874 0.4064)
			(end -0.7874 0.4064)
			(stroke
				(width 0.1524)
				(type default)
			)
			(layer "F.SilkS")
		)
		(fp_line
			(start -0.7874 -0.4064)
			(end 0.7874 -0.4064)
			(stroke
				(width 0.1524)
				(type default)
			)
			(layer "F.SilkS")
		)
		(fp_line
			(start 0.7874 -0.4064)
			(end 0.7874 0.4064)
			(stroke
				(width 0.1524)
				(type default)
			)
			(layer "F.SilkS")
		)
		(fp_line
			(start -0.67945 0.3048)
			(end -0.67945 -0.305054)
			(stroke
				(width 0.1)
				(type default)
			)
			(layer "F.Fab")
		)
		(fp_line
			(start -0.12065 0.3048)
			(end -0.67945 0.3048)
			(stroke
				(width 0.1)
				(type default)
			)
			(layer "F.Fab")
		)
		(fp_line
			(start 0.120396 0.3048)
			(end 0.120396 0.2794)
			(stroke
				(width 0.1)
				(type default)
			)
			(layer "F.Fab")
		)
		(fp_line
			(start 0.67945 0.3048)
			(end 0.120396 0.3048)
			(stroke
				(width 0.1)
				(type default)
			)
			(layer "F.Fab")
		)
		(fp_line
			(start -0.12065 0.2794)
			(end -0.12065 0.3048)
			(stroke
				(width 0.1)
				(type default)
			)
			(layer "F.Fab")
		)
		(fp_line
			(start 0.120396 0.2794)
			(end -0.12065 0.2794)
			(stroke
				(width 0.1)
				(type default)
			)
			(layer "F.Fab")
		)
		(fp_line
			(start -0.12065 -0.2794)
			(end 0.12065 -0.2794)
			(stroke
				(width 0.1)
				(type default)
			)
			(layer "F.Fab")
		)
		(fp_line
			(start 0.12065 -0.2794)
			(end 0.12065 -0.3048)
			(stroke
				(width 0.1)
				(type default)
			)
			(layer "F.Fab")
		)
		(fp_line
			(start 0.12065 -0.3048)
			(end 0.67945 -0.3048)
			(stroke
				(width 0.1)
				(type default)
			)
			(layer "F.Fab")
		)
		(fp_line
			(start 0.67945 -0.3048)
			(end 0.67945 0.3048)
			(stroke
				(width 0.1)
				(type default)
			)
			(layer "F.Fab")
		)
		(fp_line
			(start -0.67945 -0.305054)
			(end -0.12065 -0.305054)
			(stroke
				(width 0.1)
				(type default)
			)
			(layer "F.Fab")
		)
		(fp_line
			(start -0.12065 -0.305054)
			(end -0.12065 -0.2794)
			(stroke
				(width 0.1)
				(type default)
			)
			(layer "F.Fab")
		)
		(pad "1" smd circle
			(at -0.40005 0 270)
			(size 0 0)
			(layers "F.Cu" "F.Mask" "F.Paste")
			(net "RST_CPU1_SYS_N")
		)
		(pad "2" smd circle
			(at 0.40005 0 270)
			(size 0 0)
			(layers "F.Cu" "F.Mask" "F.Paste")
			(net "FM_CPU1_SYS_RESET_N")
		)
	)
	(footprint ""
		(layer "F.Cu")
		(at 48.19904 -438.753504 90)
		(property "Reference" "R2925"
			(at 0 0 90)
			(layer "F.SilkS")
			(hide yes)
			(effects
				(font
					(size 1.27 1.27)
				)
			)
		)
		(property "Value" ""
			(at 0 0 90)
			(layer "F.Fab")
			(effects
				(font
					(size 1.27 1.27)
				)
			)
		)
		(duplicate_pad_numbers_are_jumpers no)
		(fp_line
			(start 0.7874 -0.4064)
			(end 0.7874 0.4064)
			(stroke
				(width 0.1524)
				(type default)
			)
			(layer "F.SilkS")
		)
		(fp_line
			(start -0.7874 -0.4064)
			(end 0.7874 -0.4064)
			(stroke
				(width 0.1524)
				(type default)
			)
			(layer "F.SilkS")
		)
		(fp_line
			(start 0.7874 0.4064)
			(end -0.7874 0.4064)
			(stroke
				(width 0.1524)
				(type default)
			)
			(layer "F.SilkS")
		)
		(fp_line
			(start -0.7874 0.4064)
			(end -0.7874 -0.4064)
			(stroke
				(width 0.1524)
				(type default)
			)
			(layer "F.SilkS")
		)
		(fp_line
			(start -0.12065 -0.305054)
			(end -0.12065 -0.2794)
			(stroke
				(width 0.1)
				(type default)
			)
			(layer "F.Fab")
		)
		(fp_line
			(start -0.67945 -0.305054)
			(end -0.12065 -0.305054)
			(stroke
				(width 0.1)
				(type default)
			)
			(layer "F.Fab")
		)
		(fp_line
			(start 0.67945 -0.3048)
			(end 0.67945 0.3048)
			(stroke
				(width 0.1)
				(type default)
			)
			(layer "F.Fab")
		)
		(fp_line
			(start 0.12065 -0.3048)
			(end 0.67945 -0.3048)
			(stroke
				(width 0.1)
				(type default)
			)
			(layer "F.Fab")
		)
		(fp_line
			(start 0.12065 -0.2794)
			(end 0.12065 -0.3048)
			(stroke
				(width 0.1)
				(type default)
			)
			(layer "F.Fab")
		)
		(fp_line
			(start -0.12065 -0.2794)
			(end 0.12065 -0.2794)
			(stroke
				(width 0.1)
				(type default)
			)
			(layer "F.Fab")
		)
		(fp_line
			(start 0.120396 0.2794)
			(end -0.12065 0.2794)
			(stroke
				(width 0.1)
				(type default)
			)
			(layer "F.Fab")
		)
		(fp_line
			(start -0.12065 0.2794)
			(end -0.12065 0.3048)
			(stroke
				(width 0.1)
				(type default)
			)
			(layer "F.Fab")
		)
		(fp_line
			(start 0.67945 0.3048)
			(end 0.120396 0.3048)
			(stroke
				(width 0.1)
				(type default)
			)
			(layer "F.Fab")
		)
		(fp_line
			(start 0.120396 0.3048)
			(end 0.120396 0.2794)
			(stroke
				(width 0.1)
				(type default)
			)
			(layer "F.Fab")
		)
		(fp_line
			(start -0.12065 0.3048)
			(end -0.67945 0.3048)
			(stroke
				(width 0.1)
				(type default)
			)
			(layer "F.Fab")
		)
		(fp_line
			(start -0.67945 0.3048)
			(end -0.67945 -0.305054)
			(stroke
				(width 0.1)
				(type default)
			)
			(layer "F.Fab")
		)
		(pad "1" smd circle
			(at -0.40005 0 90)
			(size 0 0)
			(layers "F.Cu" "F.Mask" "F.Paste")
			(net "FM_GPU_PWR_EN_R1")
		)
		(pad "2" smd circle
			(at 0.40005 0 90)
			(size 0 0)
			(layers "F.Cu" "F.Mask" "F.Paste")
			(net "FM_GPU_PWR_EN_R_BUF")
		)
	)
	(footprint ""
		(layer "F.Cu")
		(at 175.300894 -390.53008 180)
		(property "Reference" "R861"
			(at 0 0 180)
			(layer "F.SilkS")
			(hide yes)
			(effects
				(font
					(size 1.27 1.27)
				)
			)
		)
		(property "Value" ""
			(at 0 0 180)
			(layer "F.Fab")
			(effects
				(font
					(size 1.27 1.27)
				)
			)
		)
		(duplicate_pad_numbers_are_jumpers no)
		(fp_line
			(start 0.32512 0.175006)
			(end -0.32512 0.175006)
			(stroke
				(width 0.1)
				(type default)
			)
			(layer "F.Fab")
		)
		(fp_line
			(start 0.32512 -0.175006)
			(end 0.32512 0.175006)
			(stroke
				(width 0.1)
				(type default)
			)
			(layer "F.Fab")
		)
		(fp_line
			(start -0.32512 0.175006)
			(end -0.32512 -0.175006)
			(stroke
				(width 0.1)
				(type default)
			)
			(layer "F.Fab")
		)
		(fp_line
			(start -0.32512 -0.175006)
			(end 0.32512 -0.175006)
			(stroke
				(width 0.1)
				(type default)
			)
			(layer "F.Fab")
		)
		(pad "1" smd rect
			(at -0.2667 0 180)
			(size 0.3048 0.381)
			(layers "F.Cu" "F.Mask" "F.Paste")
			(net "P1V8_CPU1_RT_1D")
		)
		(pad "2" smd rect
			(at 0.2667 0)
			(size 0.3048 0.381)
			(layers "F.Cu" "F.Mask" "F.Paste")
			(net "RT_CPU1_P2_ADDR3")
		)
	)
	(footprint ""
		(layer "F.Cu")
		(at 165.3032 -419.7096 180)
		(property "Reference" "C7503"
			(at 0 0 180)
			(layer "F.SilkS")
			(hide yes)
			(effects
				(font
					(size 1.27 1.27)
				)
			)
		)
		(property "Value" ""
			(at 0 0 180)
			(layer "F.Fab")
			(effects
				(font
					(size 1.27 1.27)
				)
			)
		)
		(duplicate_pad_numbers_are_jumpers no)
		(fp_line
			(start 0.299974 0.150114)
			(end -0.299974 0.150114)
			(stroke
				(width 0.1)
				(type default)
			)
			(layer "F.Fab")
		)
		(fp_line
			(start 0.299974 -0.150114)
			(end 0.299974 0.150114)
			(stroke
				(width 0.1)
				(type default)
			)
			(layer "F.Fab")
		)
		(fp_line
			(start -0.299974 0.150114)
			(end -0.299974 -0.150114)
			(stroke
				(width 0.1)
				(type default)
			)
			(layer "F.Fab")
		)
		(fp_line
			(start -0.299974 -0.150114)
			(end 0.299974 -0.150114)
			(stroke
				(width 0.1)
				(type default)
			)
			(layer "F.Fab")
		)
		(pad "1" smd rect
			(at -0.2667 0 180)
			(size 0.3048 0.381)
			(layers "F.Cu" "F.Mask" "F.Paste")
			(net "P1V8_CPU1_RT_1D")
		)
		(pad "2" smd rect
			(at 0.2667 0 180)
			(size 0.3048 0.381)
			(layers "F.Cu" "F.Mask" "F.Paste")
			(net "GND")
		)
	)
	(footprint ""
		(layer "F.Cu")
		(at 422.88206 -163.314888)
		(property "Reference" "H53"
			(at 2.1844 3.91287 0)
			(unlocked yes)
			(layer "F.SilkS")
			(effects
				(font
					(size 0.7874 0.5842)
					(thickness 0.1524)
				)
				(justify left)
			)
		)
		(property "Value" ""
			(at 0 0 0)
			(layer "F.Fab")
			(effects
				(font
					(size 1.27 1.27)
				)
			)
		)
		(duplicate_pad_numbers_are_jumpers no)
		(pad "1" thru_hole circle
			(at 0 0)
			(size 6.1976 6.1976)
			(drill 3.7338)
			(layers "*.Cu" "*.Mask")
			(remove_unused_layers no)
			(net "GND")
			(clearance -0.9779)
			(padstack
				(mode front_inner_back)
				(layer "Inner"
					(shape circle)
					(size 5.5372 5.5372)
					(clearance -0.6477)
				)
				(layer "B.Cu"
					(shape circle)
					(size 6.1976 6.1976)
					(clearance -0.9779)
				)
			)
		)
	)
	(footprint ""
		(layer "F.Cu")
		(at 479.35896 -202.351132 180)
		(property "Reference" "DB3"
			(at -1.527048 3.26771 0)
			(unlocked yes)
			(layer "F.SilkS")
			(effects
				(font
					(size 0.7874 0.5842)
					(thickness 0.1524)
				)
				(justify left)
			)
		)
		(property "Value" ""
			(at 0 0 180)
			(layer "F.Fab")
			(effects
				(font
					(size 1.27 1.27)
				)
			)
		)
		(duplicate_pad_numbers_are_jumpers no)
		(fp_line
			(start 3.330702 -4.771136)
			(end 0 4.011168)
			(stroke
				(width 0.1524)
				(type default)
			)
			(layer "F.SilkS")
		)
		(fp_line
			(start 0 4.011168)
			(end -3.330702 -4.771136)
			(stroke
				(width 0.1524)
				(type default)
			)
			(layer "F.SilkS")
		)
		(fp_line
			(start -3.330702 -4.771136)
			(end 3.330702 -4.771136)
			(stroke
				(width 0.1524)
				(type default)
			)
			(layer "F.SilkS")
		)
		(fp_line
			(start 3.330702 -4.771136)
			(end 0 4.011168)
			(stroke
				(width 0.1)
				(type default)
			)
			(layer "F.Fab")
		)
		(fp_line
			(start 0 4.011168)
			(end -3.330702 -4.771136)
			(stroke
				(width 0.1)
				(type default)
			)
			(layer "F.Fab")
		)
		(fp_line
			(start -3.330702 -4.771136)
			(end 3.330702 -4.771136)
			(stroke
				(width 0.1)
				(type default)
			)
			(layer "F.Fab")
		)
		(pad "1" thru_hole circle
			(at 0 0 180)
			(size 2.159 2.159)
			(drill 1.7018)
			(layers "*.Cu" "*.Mask")
			(remove_unused_layers no)
			(net "T1_GND")
			(clearance 0.0254)
			(thermal_gap 0.0254)
		)
		(pad "2" thru_hole circle
			(at -1.27 -3.348736 180)
			(size 2.159 2.159)
			(drill 1.7018)
			(layers "*.Cu" "*.Mask")
			(remove_unused_layers no)
			(net "TDR_SE_45_OHM_IN2")
			(clearance 0.0254)
			(thermal_gap 0.0254)
		)
		(pad "3" thru_hole circle
			(at 1.27 -3.348736 180)
			(size 2.159 2.159)
			(drill 1.7018)
			(layers "*.Cu" "*.Mask")
			(remove_unused_layers no)
			(net "TDR_SE_45_OHM_IN2")
			(clearance 0.0254)
			(thermal_gap 0.0254)
		)
	)
	(footprint ""
		(layer "F.Cu")
		(at 152.849326 -38.00856 180)
		(property "Reference" "R3520"
			(at 0 0 180)
			(layer "F.SilkS")
			(hide yes)
			(effects
				(font
					(size 1.27 1.27)
				)
			)
		)
		(property "Value" ""
			(at 0 0 180)
			(layer "F.Fab")
			(effects
				(font
					(size 1.27 1.27)
				)
			)
		)
		(duplicate_pad_numbers_are_jumpers no)
		(fp_line
			(start 0.7874 0.4064)
			(end -0.7874 0.4064)
			(stroke
				(width 0.1524)
				(type default)
			)
			(layer "F.SilkS")
		)
		(fp_line
			(start 0.7874 -0.4064)
			(end 0.7874 0.4064)
			(stroke
				(width 0.1524)
				(type default)
			)
			(layer "F.SilkS")
		)
		(fp_line
			(start -0.7874 0.4064)
			(end -0.7874 -0.4064)
			(stroke
				(width 0.1524)
				(type default)
			)
			(layer "F.SilkS")
		)
		(fp_line
			(start -0.7874 -0.4064)
			(end 0.7874 -0.4064)
			(stroke
				(width 0.1524)
				(type default)
			)
			(layer "F.SilkS")
		)
		(fp_line
			(start 0.67945 0.3048)
			(end 0.120396 0.3048)
			(stroke
				(width 0.1)
				(type default)
			)
			(layer "F.Fab")
		)
		(fp_line
			(start 0.67945 -0.3048)
			(end 0.67945 0.3048)
			(stroke
				(width 0.1)
				(type default)
			)
			(layer "F.Fab")
		)
		(fp_line
			(start 0.12065 -0.2794)
			(end 0.12065 -0.3048)
			(stroke
				(width 0.1)
				(type default)
			)
			(layer "F.Fab")
		)
		(fp_line
			(start 0.12065 -0.3048)
			(end 0.67945 -0.3048)
			(stroke
				(width 0.1)
				(type default)
			)
			(layer "F.Fab")
		)
		(fp_line
			(start 0.120396 0.3048)
			(end 0.120396 0.2794)
			(stroke
				(width 0.1)
				(type default)
			)
			(layer "F.Fab")
		)
		(fp_line
			(start 0.120396 0.2794)
			(end -0.12065 0.2794)
			(stroke
				(width 0.1)
				(type default)
			)
			(layer "F.Fab")
		)
		(fp_line
			(start -0.12065 0.3048)
			(end -0.67945 0.3048)
			(stroke
				(width 0.1)
				(type default)
			)
			(layer "F.Fab")
		)
		(fp_line
			(start -0.12065 0.2794)
			(end -0.12065 0.3048)
			(stroke
				(width 0.1)
				(type default)
			)
			(layer "F.Fab")
		)
		(fp_line
			(start -0.12065 -0.2794)
			(end 0.12065 -0.2794)
			(stroke
				(width 0.1)
				(type default)
			)
			(layer "F.Fab")
		)
		(fp_line
			(start -0.12065 -0.305054)
			(end -0.12065 -0.2794)
			(stroke
				(width 0.1)
				(type default)
			)
			(layer "F.Fab")
		)
		(fp_line
			(start -0.67945 0.3048)
			(end -0.67945 -0.305054)
			(stroke
				(width 0.1)
				(type default)
			)
			(layer "F.Fab")
		)
		(fp_line
			(start -0.67945 -0.305054)
			(end -0.12065 -0.305054)
			(stroke
				(width 0.1)
				(type default)
			)
			(layer "F.Fab")
		)
		(pad "1" smd circle
			(at -0.40005 0 180)
			(size 0 0)
			(layers "F.Cu" "F.Mask" "F.Paste")
			(net "P3V3_OCP_V3_2")
		)
		(pad "2" smd circle
			(at 0.40005 0 180)
			(size 0 0)
			(layers "F.Cu" "F.Mask" "F.Paste")
			(net "SMB_OCP_V3_2_3V3AUX_BUF_SDA")
		)
	)
	(footprint ""
		(layer "F.Cu")
		(at 169.220642 -92.268294 180)
		(property "Reference" "R1142"
			(at 0 0 180)
			(layer "F.SilkS")
			(hide yes)
			(effects
				(font
					(size 1.27 1.27)
				)
			)
		)
		(property "Value" ""
			(at 0 0 180)
			(layer "F.Fab")
			(effects
				(font
					(size 1.27 1.27)
				)
			)
		)
		(duplicate_pad_numbers_are_jumpers no)
		(fp_line
			(start 0.7874 0.4064)
			(end -0.7874 0.4064)
			(stroke
				(width 0.1524)
				(type default)
			)
			(layer "F.SilkS")
		)
		(fp_line
			(start 0.7874 -0.4064)
			(end 0.7874 0.4064)
			(stroke
				(width 0.1524)
				(type default)
			)
			(layer "F.SilkS")
		)
		(fp_line
			(start -0.7874 0.4064)
			(end -0.7874 -0.4064)
			(stroke
				(width 0.1524)
				(type default)
			)
			(layer "F.SilkS")
		)
		(fp_line
			(start -0.7874 -0.4064)
			(end 0.7874 -0.4064)
			(stroke
				(width 0.1524)
				(type default)
			)
			(layer "F.SilkS")
		)
		(fp_line
			(start 0.67945 0.3048)
			(end 0.120396 0.3048)
			(stroke
				(width 0.1)
				(type default)
			)
			(layer "F.Fab")
		)
		(fp_line
			(start 0.67945 -0.3048)
			(end 0.67945 0.3048)
			(stroke
				(width 0.1)
				(type default)
			)
			(layer "F.Fab")
		)
		(fp_line
			(start 0.12065 -0.2794)
			(end 0.12065 -0.3048)
			(stroke
				(width 0.1)
				(type default)
			)
			(layer "F.Fab")
		)
		(fp_line
			(start 0.12065 -0.3048)
			(end 0.67945 -0.3048)
			(stroke
				(width 0.1)
				(type default)
			)
			(layer "F.Fab")
		)
		(fp_line
			(start 0.120396 0.3048)
			(end 0.120396 0.2794)
			(stroke
				(width 0.1)
				(type default)
			)
			(layer "F.Fab")
		)
		(fp_line
			(start 0.120396 0.2794)
			(end -0.12065 0.2794)
			(stroke
				(width 0.1)
				(type default)
			)
			(layer "F.Fab")
		)
		(fp_line
			(start -0.12065 0.3048)
			(end -0.67945 0.3048)
			(stroke
				(width 0.1)
				(type default)
			)
			(layer "F.Fab")
		)
		(fp_line
			(start -0.12065 0.2794)
			(end -0.12065 0.3048)
			(stroke
				(width 0.1)
				(type default)
			)
			(layer "F.Fab")
		)
		(fp_line
			(start -0.12065 -0.2794)
			(end 0.12065 -0.2794)
			(stroke
				(width 0.1)
				(type default)
			)
			(layer "F.Fab")
		)
		(fp_line
			(start -0.12065 -0.305054)
			(end -0.12065 -0.2794)
			(stroke
				(width 0.1)
				(type default)
			)
			(layer "F.Fab")
		)
		(fp_line
			(start -0.67945 0.3048)
			(end -0.67945 -0.305054)
			(stroke
				(width 0.1)
				(type default)
			)
			(layer "F.Fab")
		)
		(fp_line
			(start -0.67945 -0.305054)
			(end -0.12065 -0.305054)
			(stroke
				(width 0.1)
				(type default)
			)
			(layer "F.Fab")
		)
		(pad "1" smd circle
			(at -0.40005 0 180)
			(size 0 0)
			(layers "F.Cu" "F.Mask" "F.Paste")
			(net "OCP_V3_1_P3V3_PWRGD")
		)
		(pad "2" smd circle
			(at 0.40005 0 180)
			(size 0 0)
			(layers "F.Cu" "F.Mask" "F.Paste")
			(net "OCP_V3_1_P3V3_R2_PWRGD")
		)
	)
)
